(kicad_pcb
	(version 20260206)
	(generator "pcbnew")
	(generator_version "10.0")
	(general
		(thickness 1.6)
		(legacy_teardrops no)
	)
	(paper "A4")
	(title_block
		(title "03242023_DA0F0TMBIJ0_F0T_Motherboard_J_brd_V01_OCP.brd")
		(comment 1 "Grand Teton / footprints 2961-2965 of 6105")
	)
	(layers
		(0 "F.Cu" signal "TOP")
		(4 "In1.Cu" signal "GND")
		(6 "In2.Cu" signal "IN1")
		(8 "In3.Cu" signal "GND1")
		(10 "In4.Cu" signal "IN2")
		(12 "In5.Cu" signal "GND2")
		(14 "In6.Cu" signal "IN3")
		(16 "In7.Cu" signal "GND3")
		(18 "In8.Cu" signal "VCC")
		(20 "In9.Cu" signal "VCC1")
		(22 "In10.Cu" signal "GND4")
		(24 "In11.Cu" signal "IN4")
		(26 "In12.Cu" signal "GND5")
		(28 "In13.Cu" signal "IN5")
		(30 "In14.Cu" signal "GND6")
		(32 "In15.Cu" signal "IN6")
		(34 "In16.Cu" signal "GND7")
		(2 "B.Cu" signal "BOTTOM")
		(9 "F.Adhes" user "F.Adhesive")
		(11 "B.Adhes" user "B.Adhesive")
		(13 "F.Paste" user "Package Geometry/Pastemask Top")
		(15 "B.Paste" user "Package Geometry/Pastemask Bottom")
		(5 "F.SilkS" user "Ref Des/Silkscreen Top")
		(7 "B.SilkS" user "Ref Des/Silkscreen Bottom")
		(1 "F.Mask" user "Board Geometry/Soldermask Top")
		(3 "B.Mask" user "Board Geometry/Soldermask Bottom")
		(17 "Dwgs.User" user "User.Drawings")
		(19 "Cmts.User" user "User.Comments")
		(21 "Eco1.User" user "User.Eco1")
		(23 "Eco2.User" user "User.Eco2")
		(25 "Edge.Cuts" user "Board Geometry/Outline")
		(27 "Margin" user)
		(31 "F.CrtYd" user "Package Geometry/Place Bound Top")
		(29 "B.CrtYd" user "Package Geometry/Place Bound Bottom")
		(35 "F.Fab" user "Ref Des/Assembly Top")
		(33 "B.Fab" user "Ref Des/Assembly Bottom")
	)
	(footprint ""
		(layer "F.Cu")
		(at 88.442038 -179.267866 180)
		(property "Reference" "R4260"
			(at 0 0 180)
			(layer "F.SilkS")
			(hide yes)
			(effects
				(font
					(size 1.27 1.27)
				)
			)
		)
		(property "Value" ""
			(at 0 0 180)
			(layer "F.Fab")
			(effects
				(font
					(size 1.27 1.27)
				)
			)
		)
		(duplicate_pad_numbers_are_jumpers no)
		(fp_line
			(start 0.7874 0.4064)
			(end -0.7874 0.4064)
			(stroke
				(width 0.1524)
				(type default)
			)
			(layer "F.SilkS")
		)
		(fp_line
			(start 0.7874 -0.4064)
			(end 0.7874 0.4064)
			(stroke
				(width 0.1524)
				(type default)
			)
			(layer "F.SilkS")
		)
		(fp_line
			(start -0.7874 0.4064)
			(end -0.7874 -0.4064)
			(stroke
				(width 0.1524)
				(type default)
			)
			(layer "F.SilkS")
		)
		(fp_line
			(start -0.7874 -0.4064)
			(end 0.7874 -0.4064)
			(stroke
				(width 0.1524)
				(type default)
			)
			(layer "F.SilkS")
		)
		(fp_line
			(start 0.67945 0.3048)
			(end 0.120396 0.3048)
			(stroke
				(width 0.1)
				(type default)
			)
			(layer "F.Fab")
		)
		(fp_line
			(start 0.67945 -0.3048)
			(end 0.67945 0.3048)
			(stroke
				(width 0.1)
				(type default)
			)
			(layer "F.Fab")
		)
		(fp_line
			(start 0.12065 -0.2794)
			(end 0.12065 -0.3048)
			(stroke
				(width 0.1)
				(type default)
			)
			(layer "F.Fab")
		)
		(fp_line
			(start 0.12065 -0.3048)
			(end 0.67945 -0.3048)
			(stroke
				(width 0.1)
				(type default)
			)
			(layer "F.Fab")
		)
		(fp_line
			(start 0.120396 0.3048)
			(end 0.120396 0.2794)
			(stroke
				(width 0.1)
				(type default)
			)
			(layer "F.Fab")
		)
		(fp_line
			(start 0.120396 0.2794)
			(end -0.12065 0.2794)
			(stroke
				(width 0.1)
				(type default)
			)
			(layer "F.Fab")
		)
		(fp_line
			(start -0.12065 0.3048)
			(end -0.67945 0.3048)
			(stroke
				(width 0.1)
				(type default)
			)
			(layer "F.Fab")
		)
		(fp_line
			(start -0.12065 0.2794)
			(end -0.12065 0.3048)
			(stroke
				(width 0.1)
				(type default)
			)
			(layer "F.Fab")
		)
		(fp_line
			(start -0.12065 -0.2794)
			(end 0.12065 -0.2794)
			(stroke
				(width 0.1)
				(type default)
			)
			(layer "F.Fab")
		)
		(fp_line
			(start -0.12065 -0.305054)
			(end -0.12065 -0.2794)
			(stroke
				(width 0.1)
				(type default)
			)
			(layer "F.Fab")
		)
		(fp_line
			(start -0.67945 0.3048)
			(end -0.67945 -0.305054)
			(stroke
				(width 0.1)
				(type default)
			)
			(layer "F.Fab")
		)
		(fp_line
			(start -0.67945 -0.305054)
			(end -0.12065 -0.305054)
			(stroke
				(width 0.1)
				(type default)
			)
			(layer "F.Fab")
		)
		(pad "1" smd circle
			(at -0.40005 0 180)
			(size 0 0)
			(layers "F.Cu" "F.Mask" "F.Paste")
			(net "PVNN_TERM_CPU0")
		)
		(pad "2" smd circle
			(at 0.40005 0 180)
			(size 0 0)
			(layers "F.Cu" "F.Mask" "F.Paste")
			(net "PD_CPU1_BIST_ENABLE")
		)
	)
	(footprint ""
		(layer "F.Cu")
		(at 21.348192 -399.532094 90)
		(property "Reference" "R3278"
			(at 0 0 90)
			(layer "F.SilkS")
			(hide yes)
			(effects
				(font
					(size 1.27 1.27)
				)
			)
		)
		(property "Value" ""
			(at 0 0 90)
			(layer "F.Fab")
			(effects
				(font
					(size 1.27 1.27)
				)
			)
		)
		(duplicate_pad_numbers_are_jumpers no)
		(fp_line
			(start 0.7874 -0.4064)
			(end 0.7874 0.4064)
			(stroke
				(width 0.1524)
				(type default)
			)
			(layer "F.SilkS")
		)
		(fp_line
			(start -0.7874 -0.4064)
			(end 0.7874 -0.4064)
			(stroke
				(width 0.1524)
				(type default)
			)
			(layer "F.SilkS")
		)
		(fp_line
			(start 0.7874 0.4064)
			(end -0.7874 0.4064)
			(stroke
				(width 0.1524)
				(type default)
			)
			(layer "F.SilkS")
		)
		(fp_line
			(start -0.7874 0.4064)
			(end -0.7874 -0.4064)
			(stroke
				(width 0.1524)
				(type default)
			)
			(layer "F.SilkS")
		)
		(fp_line
			(start -0.12065 -0.305054)
			(end -0.12065 -0.2794)
			(stroke
				(width 0.1)
				(type default)
			)
			(layer "F.Fab")
		)
		(fp_line
			(start -0.67945 -0.305054)
			(end -0.12065 -0.305054)
			(stroke
				(width 0.1)
				(type default)
			)
			(layer "F.Fab")
		)
		(fp_line
			(start 0.67945 -0.3048)
			(end 0.67945 0.3048)
			(stroke
				(width 0.1)
				(type default)
			)
			(layer "F.Fab")
		)
		(fp_line
			(start 0.12065 -0.3048)
			(end 0.67945 -0.3048)
			(stroke
				(width 0.1)
				(type default)
			)
			(layer "F.Fab")
		)
		(fp_line
			(start 0.12065 -0.2794)
			(end 0.12065 -0.3048)
			(stroke
				(width 0.1)
				(type default)
			)
			(layer "F.Fab")
		)
		(fp_line
			(start -0.12065 -0.2794)
			(end 0.12065 -0.2794)
			(stroke
				(width 0.1)
				(type default)
			)
			(layer "F.Fab")
		)
		(fp_line
			(start 0.120396 0.2794)
			(end -0.12065 0.2794)
			(stroke
				(width 0.1)
				(type default)
			)
			(layer "F.Fab")
		)
		(fp_line
			(start -0.12065 0.2794)
			(end -0.12065 0.3048)
			(stroke
				(width 0.1)
				(type default)
			)
			(layer "F.Fab")
		)
		(fp_line
			(start 0.67945 0.3048)
			(end 0.120396 0.3048)
			(stroke
				(width 0.1)
				(type default)
			)
			(layer "F.Fab")
		)
		(fp_line
			(start 0.120396 0.3048)
			(end 0.120396 0.2794)
			(stroke
				(width 0.1)
				(type default)
			)
			(layer "F.Fab")
		)
		(fp_line
			(start -0.12065 0.3048)
			(end -0.67945 0.3048)
			(stroke
				(width 0.1)
				(type default)
			)
			(layer "F.Fab")
		)
		(fp_line
			(start -0.67945 0.3048)
			(end -0.67945 -0.305054)
			(stroke
				(width 0.1)
				(type default)
			)
			(layer "F.Fab")
		)
		(pad "1" smd circle
			(at -0.40005 0 90)
			(size 0 0)
			(layers "F.Cu" "F.Mask" "F.Paste")
			(net "FM_P2E_EQA0")
		)
		(pad "2" smd circle
			(at 0.40005 0 90)
			(size 0 0)
			(layers "F.Cu" "F.Mask" "F.Paste")
			(net "GND")
		)
	)
	(footprint ""
		(layer "F.Cu")
		(at 13.12672 -74.846688)
		(property "Reference" "U242"
			(at 2.69494 1.000252 0)
			(unlocked yes)
			(layer "F.SilkS")
			(effects
				(font
					(size 0.7874 0.5842)
					(thickness 0.1524)
				)
				(justify left)
			)
		)
		(property "Value" ""
			(at 0 0 0)
			(layer "F.Fab")
			(effects
				(font
					(size 1.27 1.27)
				)
			)
		)
		(duplicate_pad_numbers_are_jumpers no)
		(fp_line
			(start -1.207008 -1.549908)
			(end -1.207008 1.549908)
			(stroke
				(width 0.1524)
				(type default)
			)
			(layer "F.SilkS")
		)
		(fp_line
			(start -1.207008 1.549908)
			(end 1.207008 1.549908)
			(stroke
				(width 0.1524)
				(type default)
			)
			(layer "F.SilkS")
		)
		(fp_line
			(start -0.762508 -1.549908)
			(end -1.207008 -1.549908)
			(stroke
				(width 0.1524)
				(type default)
			)
			(layer "F.SilkS")
		)
		(fp_line
			(start 0 -0.635)
			(end -0.762508 -1.549908)
			(stroke
				(width 0.1524)
				(type default)
			)
			(layer "F.SilkS")
		)
		(fp_line
			(start 0.762508 -1.549908)
			(end 0 -0.635)
			(stroke
				(width 0.1524)
				(type default)
			)
			(layer "F.SilkS")
		)
		(fp_line
			(start 1.207008 -1.549908)
			(end 0.762508 -1.549908)
			(stroke
				(width 0.1524)
				(type default)
			)
			(layer "F.SilkS")
		)
		(fp_line
			(start 1.207008 1.549908)
			(end 1.207008 -1.549908)
			(stroke
				(width 0.1524)
				(type default)
			)
			(layer "F.SilkS")
		)
		(fp_poly
			(pts
				(xy -1.41351 -2.42062) (xy -1.92151 -1.40462) (xy -2.42951 -2.42062)
			)
			(stroke
				(width 0)
				(type default)
			)
			(fill yes)
			(layer "F.SilkS")
		)
		(fp_line
			(start -1.549908 -1.549908)
			(end -1.549908 1.549908)
			(stroke
				(width 0.1)
				(type default)
			)
			(layer "F.Fab")
		)
		(fp_line
			(start -1.549908 1.549908)
			(end 1.549908 1.549908)
			(stroke
				(width 0.1)
				(type default)
			)
			(layer "F.Fab")
		)
		(fp_line
			(start 1.549908 -1.549908)
			(end -1.549908 -1.549908)
			(stroke
				(width 0.1)
				(type default)
			)
			(layer "F.Fab")
		)
		(fp_line
			(start 1.549908 1.549908)
			(end 1.549908 -1.549908)
			(stroke
				(width 0.1)
				(type default)
			)
			(layer "F.Fab")
		)
		(fp_poly
			(pts
				(xy -3.4036 -1.53289) (xy -3.4036 -0.51689) (xy -2.3876 -1.02489)
			)
			(stroke
				(width 0)
				(type default)
			)
			(fill yes)
			(layer "F.Fab")
		)
		(pad "1" smd rect
			(at -1.774952 -1.02489 270)
			(size 0.508 0.8636)
			(layers "F.Cu" "F.Mask" "F.Paste")
			(net "OCP_SFF_PRSNT01_R_N")
		)
		(pad "2" smd rect
			(at -1.774952 -0.32512 270)
			(size 0.4064 0.8636)
			(layers "F.Cu" "F.Mask" "F.Paste")
			(net "OCP_SFF_PRSNT23_R_N")
		)
		(pad "3" smd rect
			(at -1.774952 0.32512 270)
			(size 0.4064 0.8636)
			(layers "F.Cu" "F.Mask" "F.Paste")
			(net "OCP_V3_2_PRSNT_ALL_R_N")
		)
		(pad "4" smd rect
			(at -1.774952 1.02489 270)
			(size 0.508 0.8636)
			(layers "F.Cu" "F.Mask" "F.Paste")
			(net "GND")
		)
		(pad "5" smd rect
			(at 1.774952 1.02489 270)
			(size 0.508 0.8636)
			(layers "F.Cu" "F.Mask" "F.Paste")
			(net "OCP_V3_2_PRSNT01_R_N")
		)
		(pad "6" smd rect
			(at 1.774952 0.32512 270)
			(size 0.4064 0.8636)
			(layers "F.Cu" "F.Mask" "F.Paste")
			(net "OCP_V3_2_PRSNT23_R_N")
		)
		(pad "7" smd rect
			(at 1.774952 -0.32512 270)
			(size 0.4064 0.8636)
			(layers "F.Cu" "F.Mask" "F.Paste")
			(net "OCP_SFF_PRSNT_ALL_R_N")
		)
		(pad "8" smd rect
			(at 1.774952 -1.02489 270)
			(size 0.508 0.8636)
			(layers "F.Cu" "F.Mask" "F.Paste")
			(net "P3V3_AUX")
		)
	)
	(footprint ""
		(layer "F.Cu")
		(at 380.341886 -71.126858)
		(property "Reference" "PR396"
			(at 0 0 0)
			(layer "F.SilkS")
			(hide yes)
			(effects
				(font
					(size 1.27 1.27)
				)
			)
		)
		(property "Value" ""
			(at 0 0 0)
			(layer "F.Fab")
			(effects
				(font
					(size 1.27 1.27)
				)
			)
		)
		(duplicate_pad_numbers_are_jumpers no)
		(fp_line
			(start -0.7874 -0.4064)
			(end 0.7874 -0.4064)
			(stroke
				(width 0.1524)
				(type default)
			)
			(layer "F.SilkS")
		)
		(fp_line
			(start -0.7874 0.4064)
			(end -0.7874 -0.4064)
			(stroke
				(width 0.1524)
				(type default)
			)
			(layer "F.SilkS")
		)
		(fp_line
			(start 0.7874 -0.4064)
			(end 0.7874 0.4064)
			(stroke
				(width 0.1524)
				(type default)
			)
			(layer "F.SilkS")
		)
		(fp_line
			(start 0.7874 0.4064)
			(end -0.7874 0.4064)
			(stroke
				(width 0.1524)
				(type default)
			)
			(layer "F.SilkS")
		)
		(fp_line
			(start -0.67945 -0.305054)
			(end -0.12065 -0.305054)
			(stroke
				(width 0.1)
				(type default)
			)
			(layer "F.Fab")
		)
		(fp_line
			(start -0.67945 0.3048)
			(end -0.67945 -0.305054)
			(stroke
				(width 0.1)
				(type default)
			)
			(layer "F.Fab")
		)
		(fp_line
			(start -0.12065 -0.305054)
			(end -0.12065 -0.2794)
			(stroke
				(width 0.1)
				(type default)
			)
			(layer "F.Fab")
		)
		(fp_line
			(start -0.12065 -0.2794)
			(end 0.12065 -0.2794)
			(stroke
				(width 0.1)
				(type default)
			)
			(layer "F.Fab")
		)
		(fp_line
			(start -0.12065 0.2794)
			(end -0.12065 0.3048)
			(stroke
				(width 0.1)
				(type default)
			)
			(layer "F.Fab")
		)
		(fp_line
			(start -0.12065 0.3048)
			(end -0.67945 0.3048)
			(stroke
				(width 0.1)
				(type default)
			)
			(layer "F.Fab")
		)
		(fp_line
			(start 0.120396 0.2794)
			(end -0.12065 0.2794)
			(stroke
				(width 0.1)
				(type default)
			)
			(layer "F.Fab")
		)
		(fp_line
			(start 0.120396 0.3048)
			(end 0.120396 0.2794)
			(stroke
				(width 0.1)
				(type default)
			)
			(layer "F.Fab")
		)
		(fp_line
			(start 0.12065 -0.3048)
			(end 0.67945 -0.3048)
			(stroke
				(width 0.1)
				(type default)
			)
			(layer "F.Fab")
		)
		(fp_line
			(start 0.12065 -0.2794)
			(end 0.12065 -0.3048)
			(stroke
				(width 0.1)
				(type default)
			)
			(layer "F.Fab")
		)
		(fp_line
			(start 0.67945 -0.3048)
			(end 0.67945 0.3048)
			(stroke
				(width 0.1)
				(type default)
			)
			(layer "F.Fab")
		)
		(fp_line
			(start 0.67945 0.3048)
			(end 0.120396 0.3048)
			(stroke
				(width 0.1)
				(type default)
			)
			(layer "F.Fab")
		)
		(pad "1" smd circle
			(at -0.40005 0)
			(size 0 0)
			(layers "F.Cu" "F.Mask" "F.Paste")
			(net "P5V_AUX")
		)
		(pad "2" smd circle
			(at 0.40005 0)
			(size 0 0)
			(layers "F.Cu" "F.Mask" "F.Paste")
			(net "PVCC1_AUX")
		)
	)
	(footprint ""
		(layer "F.Cu")
		(at 228.816662 -123.167902 180)
		(property "Reference" "R1273"
			(at 0 0 180)
			(layer "F.SilkS")
			(hide yes)
			(effects
				(font
					(size 1.27 1.27)
				)
			)
		)
		(property "Value" ""
			(at 0 0 180)
			(layer "F.Fab")
			(effects
				(font
					(size 1.27 1.27)
				)
			)
		)
		(duplicate_pad_numbers_are_jumpers no)
		(fp_line
			(start 0.7874 0.4064)
			(end -0.7874 0.4064)
			(stroke
				(width 0.1524)
				(type default)
			)
			(layer "F.SilkS")
		)
		(fp_line
			(start 0.7874 -0.087122)
			(end 0.7874 0.4064)
			(stroke
				(width 0.1524)
				(type default)
			)
			(layer "F.SilkS")
		)
		(fp_line
			(start -0.507238 -0.4064)
			(end 0.610362 -0.4064)
			(stroke
				(width 0.1524)
				(type default)
			)
			(layer "F.SilkS")
		)
		(fp_line
			(start -0.7874 0.4064)
			(end -0.7874 0.011938)
			(stroke
				(width 0.1524)
				(type default)
			)
			(layer "F.SilkS")
		)
		(fp_line
			(start 0.67945 0.3048)
			(end 0.120396 0.3048)
			(stroke
				(width 0.1)
				(type default)
			)
			(layer "F.Fab")
		)
		(fp_line
			(start 0.67945 -0.3048)
			(end 0.67945 0.3048)
			(stroke
				(width 0.1)
				(type default)
			)
			(layer "F.Fab")
		)
		(fp_line
			(start 0.12065 -0.2794)
			(end 0.12065 -0.3048)
			(stroke
				(width 0.1)
				(type default)
			)
			(layer "F.Fab")
		)
		(fp_line
			(start 0.12065 -0.3048)
			(end 0.67945 -0.3048)
			(stroke
				(width 0.1)
				(type default)
			)
			(layer "F.Fab")
		)
		(fp_line
			(start 0.120396 0.3048)
			(end 0.120396 0.2794)
			(stroke
				(width 0.1)
				(type default)
			)
			(layer "F.Fab")
		)
		(fp_line
			(start 0.120396 0.2794)
			(end -0.12065 0.2794)
			(stroke
				(width 0.1)
				(type default)
			)
			(layer "F.Fab")
		)
		(fp_line
			(start -0.12065 0.3048)
			(end -0.67945 0.3048)
			(stroke
				(width 0.1)
				(type default)
			)
			(layer "F.Fab")
		)
		(fp_line
			(start -0.12065 0.2794)
			(end -0.12065 0.3048)
			(stroke
				(width 0.1)
				(type default)
			)
			(layer "F.Fab")
		)
		(fp_line
			(start -0.12065 -0.2794)
			(end 0.12065 -0.2794)
			(stroke
				(width 0.1)
				(type default)
			)
			(layer "F.Fab")
		)
		(fp_line
			(start -0.12065 -0.305054)
			(end -0.12065 -0.2794)
			(stroke
				(width 0.1)
				(type default)
			)
			(layer "F.Fab")
		)
		(fp_line
			(start -0.67945 0.3048)
			(end -0.67945 -0.305054)
			(stroke
				(width 0.1)
				(type default)
			)
			(layer "F.Fab")
		)
		(fp_line
			(start -0.67945 -0.305054)
			(end -0.12065 -0.305054)
			(stroke
				(width 0.1)
				(type default)
			)
			(layer "F.Fab")
		)
		(pad "1" smd circle
			(at -0.40005 0 180)
			(size 0 0)
			(layers "F.Cu" "F.Mask" "F.Paste")
			(net "CLK_100M_OCP_SFF_2_R_DP")
		)
		(pad "2" smd circle
			(at 0.40005 0 180)
			(size 0 0)
			(layers "F.Cu" "F.Mask" "F.Paste")
			(net "CLK_100M_OCP_SFF_2_DP")
		)
	)
)
